# BASEBOARD_FAB2 (Tioga Pass) — schematic netlist excerpt (pin names and nets, part order shuffled) for the footprints in the layout excerpt that follows; sources: Cadence DE-HDL packaged netlist, KiCad conversion of Wiwynn_Tioga_Pass_MB.brd

R2L14  RES  0.0 5% CHIP  pkg 0402  page 235 : A = P3V3_STBY ; B = VR_PVNN_PCH_VDD

T1D23  TEST-PAD-12P-1-GP-U  pkg DISCRET-GB1  page 258
  DP  = L14_85OHM_10INCH_DP
  DN  = L14_85OHM_10INCH_DN
  GND(0)  = GND
  GND(1)  = GND
  GND(2)  = GND
  GND(3)  = GND
  GND(4)  = GND
  GND(5)  = GND
  GND(6)  = GND
  GND(7)  = GND
  GND(8)  = GND
  GND(9)  = GND

(kicad_pcb
	(version 20260206)
	(generator "pcbnew")
	(generator_version "10.0")
	(general
		(thickness 1.6)
		(legacy_teardrops no)
	)
	(paper "A4")
	(title_block
		(title "Wiwynn_Tioga_Pass_MB.brd")
		(comment 1 "Tioga Pass / footprints 4446-4447 of 4770")
	)
	(layers
		(0 "F.Cu" signal "TOP")
		(4 "In1.Cu" signal "L2GND")
		(6 "In2.Cu" signal "L3")
		(8 "In3.Cu" signal "L4GND")
		(10 "In4.Cu" signal "L5")
		(12 "In5.Cu" signal "L6GND")
		(14 "In6.Cu" signal "L7VCC")
		(16 "In7.Cu" signal "L8VCC")
		(18 "In8.Cu" signal "L9GND")
		(20 "In9.Cu" signal "L10")
		(22 "In10.Cu" signal "L11GND")
		(24 "In11.Cu" signal "L12")
		(26 "In12.Cu" signal "L13GND")
		(2 "B.Cu" signal "BOTTOM")
		(9 "F.Adhes" user "F.Adhesive")
		(11 "B.Adhes" user "B.Adhesive")
		(13 "F.Paste" user "Package Geometry/Pastemask Top")
		(15 "B.Paste" user "Package Geometry/Pastemask Bottom")
		(5 "F.SilkS" user "Ref Des/Silkscreen Top")
		(7 "B.SilkS" user "Ref Des/Silkscreen Bottom")
		(1 "F.Mask" user "Board Geometry/Soldermask Top")
		(3 "B.Mask" user "Board Geometry/Soldermask Bottom")
		(17 "Dwgs.User" user "User.Drawings")
		(19 "Cmts.User" user "User.Comments")
		(21 "Eco1.User" user "User.Eco1")
		(23 "Eco2.User" user "User.Eco2")
		(25 "Edge.Cuts" user "Board Geometry/Outline")
		(27 "Margin" user)
		(31 "F.CrtYd" user "Package Geometry/Place Bound Top")
		(29 "B.CrtYd" user "Package Geometry/Place Bound Bottom")
		(35 "F.Fab" user "Ref Des/Assembly Top")
		(33 "B.Fab" user "Ref Des/Assembly Bottom")
	)
	(footprint ""
		(layer "B.Cu")
		(at 156.539692 -164.904674 -90)
		(property "Reference" "T1D23"
			(at 0 0 90)
			(layer "B.SilkS")
			(hide yes)
			(effects
				(font
					(size 1.27 1.27)
				)
				(justify mirror)
			)
		)
		(property "Value" "*"
			(at 3.4036 -4.46405 270)
			(unlocked yes)
			(layer "B.Fab")
			(hide yes)
			(effects
				(font
					(size 0.889 0.889)
					(thickness 0.1524)
				)
				(justify mirror)
			)
		)
		(property "Device Type" "TEST-PAD-12P-1-GP-U_DISCRET-GBA"
			(at 3.4036 -5.98805 270)
			(unlocked yes)
			(layer "B.Fab")
			(hide yes)
			(effects
				(font
					(size 0.889 0.889)
					(thickness 0.1524)
				)
				(justify mirror)
			)
		)
		(duplicate_pad_numbers_are_jumpers no)
		(fp_line
			(start -2.3622 3.4798)
			(end 2.3876 3.4798)
			(stroke
				(width 0.1524)
				(type default)
			)
			(layer "B.SilkS")
		)
		(fp_line
			(start 2.3876 3.4798)
			(end 2.3876 -4.826)
			(stroke
				(width 0.1524)
				(type default)
			)
			(layer "B.SilkS")
		)
		(fp_line
			(start -2.3622 -4.826)
			(end -2.3622 3.4798)
			(stroke
				(width 0.1524)
				(type default)
			)
			(layer "B.SilkS")
		)
		(fp_line
			(start 2.3876 -4.826)
			(end -2.3622 -4.826)
			(stroke
				(width 0.1524)
				(type default)
			)
			(layer "B.SilkS")
		)
		(fp_rect
			(start 2.6416 3.7338)
			(end -2.6162 -5.08)
			(stroke
				(width 0)
				(type default)
			)
			(fill no)
			(layer "B.CrtYd")
		)
		(fp_rect
			(start 2.6416 3.7338)
			(end -2.6162 -5.08)
			(stroke
				(width 0)
				(type default)
			)
			(fill no)
			(layer "B.Fab")
		)
		(pad "1" smd circle
			(at -0.496824 -1.301496 90)
			(size 0.6604 0.6604)
			(layers "B.Cu" "B.Mask" "B.Paste")
			(net "L14_85OHM_10INCH_DP")
		)
		(pad "2" smd circle
			(at 0.503936 -1.301496 90)
			(size 0.6604 0.6604)
			(layers "B.Cu" "B.Mask" "B.Paste")
			(net "L14_85OHM_10INCH_DN")
		)
		(pad "3" smd custom
			(at 0.00889 0.370078 90)
			(size 0.74295 0.74295)
			(layers "B.Cu" "B.Mask" "B.Paste")
			(net "GND")
			(options
				(clearance outline)
				(anchor circle)
			)
			(primitives
				(gr_poly
					(pts
						(xy -2.1209 -1.4859) (xy 2.1209 -1.4859) (xy 2.1209 1.4859) (xy 1.08585 1.4859) (xy 1.08585 0.4699)
						(xy -1.08585 0.4699) (xy -1.08585 1.4859) (xy -2.1209 1.4859)
					)
					(width 0)
					(fill yes)
				)
			)
		)
		(pad "4" thru_hole circle
			(at -1.266444 -3.851656 90)
			(size 1.4478 1.4478)
			(drill 1.0414)
			(layers "*.Cu" "*.Mask")
			(remove_unused_layers no)
			(net "GND")
			(clearance 0.1524)
			(thermal_gap 0.1524)
		)
		(pad "5" thru_hole circle
			(at 1.273556 -3.851656 90)
			(size 1.4478 1.4478)
			(drill 1.0414)
			(layers "*.Cu" "*.Mask")
			(remove_unused_layers no)
			(net "GND")
			(clearance 0.1524)
			(thermal_gap 0.1524)
		)
		(pad "6" thru_hole circle
			(at -1.266444 2.498344 90)
			(size 1.4478 1.4478)
			(drill 1.0414)
			(layers "*.Cu" "*.Mask")
			(remove_unused_layers no)
			(net "GND")
			(clearance 0.1524)
			(thermal_gap 0.1524)
		)
		(pad "7" thru_hole circle
			(at 1.273556 2.498344 90)
			(size 1.4478 1.4478)
			(drill 1.0414)
			(layers "*.Cu" "*.Mask")
			(remove_unused_layers no)
			(net "GND")
			(clearance 0.1524)
			(thermal_gap 0.1524)
		)
		(pad "8" thru_hole circle
			(at -1.27 -0.4572 90)
			(size 0.7112 0.7112)
			(drill 0.4064)
			(layers "*.Cu" "*.Mask")
			(remove_unused_layers no)
			(net "GND")
			(clearance 0.1016)
			(thermal_gap 0.1016)
		)
		(pad "9" thru_hole circle
			(at -1.27 0.762 90)
			(size 0.7112 0.7112)
			(drill 0.4064)
			(layers "*.Cu" "*.Mask")
			(remove_unused_layers no)
			(net "GND")
			(clearance 0.1016)
			(thermal_gap 0.1016)
		)
		(pad "10" thru_hole circle
			(at 0.0254 0.762 90)
			(size 0.7112 0.7112)
			(drill 0.4064)
			(layers "*.Cu" "*.Mask")
			(remove_unused_layers no)
			(net "GND")
			(clearance 0.1016)
			(thermal_gap 0.1016)
		)
		(pad "11" thru_hole circle
			(at 1.27 0.762 90)
			(size 0.7112 0.7112)
			(drill 0.4064)
			(layers "*.Cu" "*.Mask")
			(remove_unused_layers no)
			(net "GND")
			(clearance 0.1016)
			(thermal_gap 0.1016)
		)
		(pad "12" thru_hole circle
			(at 1.27 -0.4572 90)
			(size 0.7112 0.7112)
			(drill 0.4064)
			(layers "*.Cu" "*.Mask")
			(remove_unused_layers no)
			(net "GND")
			(clearance 0.1016)
			(thermal_gap 0.1016)
		)
	)
	(footprint ""
		(layer "B.Cu")
		(at 394.175234 -150.95474 -90)
		(property "Reference" "R2L14"
			(at 0 0 90)
			(layer "B.SilkS")
			(hide yes)
			(effects
				(font
					(size 1.27 1.27)
				)
				(justify mirror)
			)
		)
		(property "Value" ""
			(at 0 0 90)
			(layer "B.Fab")
			(effects
				(font
					(size 1.27 1.27)
				)
				(justify mirror)
			)
		)
		(duplicate_pad_numbers_are_jumpers no)
		(fp_poly
			(pts
				(xy 0.2794 -0.1016) (xy -0.2794 -0.1016) (xy -0.2794 0.9906) (xy 0.2794 0.9906)
			)
			(stroke
				(width 0)
				(type default)
			)
			(fill no)
			(layer "B.CrtYd")
		)
		(fp_line
			(start -0.2794 0.9906)
			(end -0.2794 -0.1016)
			(stroke
				(width 0.1)
				(type default)
			)
			(layer "B.Fab")
		)
		(fp_line
			(start 0.2794 0.9906)
			(end -0.2794 0.9906)
			(stroke
				(width 0.1)
				(type default)
			)
			(layer "B.Fab")
		)
		(fp_line
			(start -0.2794 -0.1016)
			(end 0.2794 -0.1016)
			(stroke
				(width 0.1)
				(type default)
			)
			(layer "B.Fab")
		)
		(fp_line
			(start 0.2794 -0.1016)
			(end 0.2794 0.9906)
			(stroke
				(width 0.1)
				(type default)
			)
			(layer "B.Fab")
		)
		(pad "1" smd rect
			(at 0 0 90)
			(size 0.508 0.508)
			(layers "B.Cu" "B.Mask" "B.Paste")
			(net "P3V3_STBY")
		)
		(pad "2" smd rect
			(at 0 0.889 90)
			(size 0.508 0.508)
			(layers "B.Cu" "B.Mask" "B.Paste")
			(net "VR_PVNN_PCH_VDD")
		)
		(zone
			(layer "B.Cu")
			(hatch none 0.5)
			(connect_pads
				(clearance 0)
			)
			(min_thickness 0.25)
			(keepout
				(tracks not_allowed)
				(vias allowed)
				(pads allowed)
				(copperpour not_allowed)
				(footprints allowed)
			)
			(placement
				(enabled no)
				(sheetname "")
			)
			(fill
				(thermal_gap 0.5)
				(thermal_bridge_width 0.5)
				(island_removal_mode 0)
			)
			(polygon
				(pts
					(xy 393.540234 -150.70074) (xy 393.540234 -151.20874) (xy 393.921234 -151.20874) (xy 393.921234 -150.70074)
				)
			)
		)
		(zone
			(layer "B.Cu")
			(hatch none 0.5)
			(connect_pads
				(clearance 0)
			)
			(min_thickness 0.25)
			(keepout
				(tracks allowed)
				(vias not_allowed)
				(pads allowed)
				(copperpour not_allowed)
				(footprints allowed)
			)
			(placement
				(enabled no)
				(sheetname "")
			)
			(fill
				(thermal_gap 0.5)
				(thermal_bridge_width 0.5)
				(island_removal_mode 0)
			)
			(polygon
				(pts
					(xy 393.921234 -150.70074) (xy 393.921234 -151.20874) (xy 393.540234 -151.20874) (xy 393.540234 -150.70074)
				)
			)
		)
	)
)
